(kicad_pcb
	(version 20260206)
	(generator "pcbnew")
	(generator_version "10.0")
	(general
		(thickness 1.6)
		(legacy_teardrops no)
	)
	(paper "A4")
	(title_block
		(title "m-2 — Lightning_M.2_BRD.brd")
		(comment 1 "Lightning (Wiwynn / Facebook NVMe JBOF) / footprints 145-145 of 157")
	)
	(layers
		(0 "F.Cu" signal "TOP")
		(4 "In1.Cu" signal "L2GND")
		(6 "In2.Cu" signal "L3")
		(8 "In3.Cu" signal "L4GND")
		(10 "In4.Cu" signal "L5GND")
		(12 "In5.Cu" signal "L6")
		(14 "In6.Cu" signal "L7GND")
		(2 "B.Cu" signal "BOTTOM")
		(9 "F.Adhes" user "F.Adhesive")
		(11 "B.Adhes" user "B.Adhesive")
		(13 "F.Paste" user "Package Geometry/Pastemask Top")
		(15 "B.Paste" user "Package Geometry/Pastemask Bottom")
		(5 "F.SilkS" user "Ref Des/Silkscreen Top")
		(7 "B.SilkS" user "Ref Des/Silkscreen Bottom")
		(1 "F.Mask" user "Board Geometry/Soldermask Top")
		(3 "B.Mask" user "Board Geometry/Soldermask Bottom")
		(17 "Dwgs.User" user "User.Drawings")
		(19 "Cmts.User" user "User.Comments")
		(21 "Eco1.User" user "User.Eco1")
		(23 "Eco2.User" user "User.Eco2")
		(25 "Edge.Cuts" user "Board Geometry/Outline")
		(27 "Margin" user)
		(31 "F.CrtYd" user "Package Geometry/Place Bound Top")
		(29 "B.CrtYd" user "Package Geometry/Place Bound Bottom")
		(35 "F.Fab" user "Ref Des/Assembly Top")
		(33 "B.Fab" user "Ref Des/Assembly Bottom")
	)
	(footprint ""
		(layer "B.Cu")
		(at 44.782994 -76.2 180)
		(property "Reference" "PR35"
			(at 0 0 0)
			(layer "B.SilkS")
			(hide yes)
			(effects
				(font
					(size 1.27 1.27)
				)
				(justify mirror)
			)
		)
		(property "Value" "619KR2F-GP"
			(at -0.064008 -3.993896 180)
			(unlocked yes)
			(layer "B.Fab")
			(hide yes)
			(effects
				(font
					(size 1.016 1.016)
					(thickness 0.1524)
				)
				(justify mirror)
			)
		)
		(property "Device Type" "R402H16"
			(at -0.064008 -5.517896 180)
			(unlocked yes)
			(layer "B.Fab")
			(hide yes)
			(effects
				(font
					(size 1.016 1.016)
					(thickness 0.1524)
				)
				(justify mirror)
			)
		)
		(duplicate_pad_numbers_are_jumpers no)
		(fp_line
			(start 0.508 -0.9398)
			(end 0.508 0.9398)
			(stroke
				(width 0.1524)
				(type default)
			)
			(layer "B.SilkS")
		)
		(fp_line
			(start -0.508 -0.9398)
			(end 0.508 -0.9398)
			(stroke
				(width 0.1524)
				(type default)
			)
			(layer "B.SilkS")
		)
		(fp_rect
			(start 0.508 0.9398)
			(end -0.508 -0.9398)
			(stroke
				(width 0)
				(type default)
			)
			(fill no)
			(layer "B.CrtYd")
		)
		(fp_rect
			(start 0.508 0.9398)
			(end -0.508 -0.9398)
			(stroke
				(width 0)
				(type default)
			)
			(fill no)
			(layer "B.Fab")
		)
		(pad "1" smd custom
			(at 0 -0.4445)
			(size 0.1397 0.1397)
			(layers "B.Cu" "B.Mask" "B.Paste")
			(net "AGND_P3V3_DEV")
			(options
				(clearance outline)
				(anchor circle)
			)
			(primitives
				(gr_poly
					(pts
						(arc
							(start -0.1778 0.2794)
							(mid -0.249642 0.249642)
							(end -0.2794 0.1778)
						)
						(arc
							(start -0.2794 -0.1778)
							(mid -0.249642 -0.249642)
							(end -0.1778 -0.2794)
						)
						(arc
							(start 0.1778 -0.2794)
							(mid 0.249642 -0.249642)
							(end 0.2794 -0.1778)
						)
						(arc
							(start 0.2794 0.1778)
							(mid 0.249642 0.249642)
							(end 0.1778 0.2794)
						)
					)
					(width 0)
					(fill yes)
				)
			)
		)
		(pad "2" smd custom
			(at 0 0.4445)
			(size 0.1397 0.1397)
			(layers "B.Cu" "B.Mask" "B.Paste")
			(net "P3V3_DEV_RF")
			(options
				(clearance outline)
				(anchor circle)
			)
			(primitives
				(gr_poly
					(pts
						(arc
							(start -0.1778 0.2794)
							(mid -0.249642 0.249642)
							(end -0.2794 0.1778)
						)
						(arc
							(start -0.2794 -0.1778)
							(mid -0.249642 -0.249642)
							(end -0.1778 -0.2794)
						)
						(arc
							(start 0.1778 -0.2794)
							(mid 0.249642 -0.249642)
							(end 0.2794 -0.1778)
						)
						(arc
							(start 0.2794 0.1778)
							(mid 0.249642 0.249642)
							(end 0.1778 0.2794)
						)
					)
					(width 0)
					(fill yes)
				)
			)
		)
	)
)
